(kicad_pcb
	(version 20260206)
	(generator "pcbnew")
	(generator_version "10.0")
	(general
		(thickness 1.6)
		(legacy_teardrops no)
	)
	(paper "A4")
	(title_block
		(title "03242023_DA0F0TMBIJ0_F0T_Motherboard_J_brd_V01_OCP.brd")
		(comment 1 "Grand Teton / footprints 5679-5685 of 6105")
	)
	(layers
		(0 "F.Cu" signal "TOP")
		(4 "In1.Cu" signal "GND")
		(6 "In2.Cu" signal "IN1")
		(8 "In3.Cu" signal "GND1")
		(10 "In4.Cu" signal "IN2")
		(12 "In5.Cu" signal "GND2")
		(14 "In6.Cu" signal "IN3")
		(16 "In7.Cu" signal "GND3")
		(18 "In8.Cu" signal "VCC")
		(20 "In9.Cu" signal "VCC1")
		(22 "In10.Cu" signal "GND4")
		(24 "In11.Cu" signal "IN4")
		(26 "In12.Cu" signal "GND5")
		(28 "In13.Cu" signal "IN5")
		(30 "In14.Cu" signal "GND6")
		(32 "In15.Cu" signal "IN6")
		(34 "In16.Cu" signal "GND7")
		(2 "B.Cu" signal "BOTTOM")
		(9 "F.Adhes" user "F.Adhesive")
		(11 "B.Adhes" user "B.Adhesive")
		(13 "F.Paste" user "Package Geometry/Pastemask Top")
		(15 "B.Paste" user "Package Geometry/Pastemask Bottom")
		(5 "F.SilkS" user "Ref Des/Silkscreen Top")
		(7 "B.SilkS" user "Ref Des/Silkscreen Bottom")
		(1 "F.Mask" user "Board Geometry/Soldermask Top")
		(3 "B.Mask" user "Board Geometry/Soldermask Bottom")
		(17 "Dwgs.User" user "User.Drawings")
		(19 "Cmts.User" user "User.Comments")
		(21 "Eco1.User" user "User.Eco1")
		(23 "Eco2.User" user "User.Eco2")
		(25 "Edge.Cuts" user "Board Geometry/Outline")
		(27 "Margin" user)
		(31 "F.CrtYd" user "Package Geometry/Place Bound Top")
		(29 "B.CrtYd" user "Package Geometry/Place Bound Bottom")
		(35 "F.Fab" user "Ref Des/Assembly Top")
		(33 "B.Fab" user "Ref Des/Assembly Bottom")
	)
	(footprint ""
		(layer "B.Cu")
		(at 349.344742 -212.049614 180)
		(property "Reference" "C519"
			(at 0 0 0)
			(layer "B.SilkS")
			(hide yes)
			(effects
				(font
					(size 1.27 1.27)
				)
				(justify mirror)
			)
		)
		(property "Value" ""
			(at 0 0 0)
			(layer "B.Fab")
			(effects
				(font
					(size 1.27 1.27)
				)
				(justify mirror)
			)
		)
		(duplicate_pad_numbers_are_jumpers no)
		(fp_line
			(start 1.2954 0.5842)
			(end 1.2954 -0.5842)
			(stroke
				(width 0.1524)
				(type default)
			)
			(layer "B.SilkS")
		)
		(fp_line
			(start 1.2954 -0.5842)
			(end -1.2954 -0.5842)
			(stroke
				(width 0.1524)
				(type default)
			)
			(layer "B.SilkS")
		)
		(fp_line
			(start 0 -0.5842)
			(end 0 0.5842)
			(stroke
				(width 0.1524)
				(type default)
			)
			(layer "B.SilkS")
		)
		(fp_line
			(start -1.2954 0.5842)
			(end 1.2954 0.5842)
			(stroke
				(width 0.1524)
				(type default)
			)
			(layer "B.SilkS")
		)
		(fp_line
			(start -1.2954 -0.5842)
			(end -1.2954 0.5842)
			(stroke
				(width 0.1524)
				(type default)
			)
			(layer "B.SilkS")
		)
		(fp_line
			(start 1.1938 0.4064)
			(end 1.1938 -0.4064)
			(stroke
				(width 0.1)
				(type default)
			)
			(layer "B.Fab")
		)
		(fp_line
			(start 1.1938 -0.4064)
			(end 0.8636 -0.4064)
			(stroke
				(width 0.1)
				(type default)
			)
			(layer "B.Fab")
		)
		(fp_line
			(start 0.8636 0.4572)
			(end 0.8636 0.4064)
			(stroke
				(width 0.1)
				(type default)
			)
			(layer "B.Fab")
		)
		(fp_line
			(start 0.8636 0.4064)
			(end 1.1938 0.4064)
			(stroke
				(width 0.1)
				(type default)
			)
			(layer "B.Fab")
		)
		(fp_line
			(start 0.8636 -0.4064)
			(end 0.8636 -0.4572)
			(stroke
				(width 0.1)
				(type default)
			)
			(layer "B.Fab")
		)
		(fp_line
			(start 0.8636 -0.4572)
			(end -0.8636 -0.4572)
			(stroke
				(width 0.1)
				(type default)
			)
			(layer "B.Fab")
		)
		(fp_line
			(start -0.8636 0.4572)
			(end 0.8636 0.4572)
			(stroke
				(width 0.1)
				(type default)
			)
			(layer "B.Fab")
		)
		(fp_line
			(start -0.8636 0.4064)
			(end -0.8636 0.4572)
			(stroke
				(width 0.1)
				(type default)
			)
			(layer "B.Fab")
		)
		(fp_line
			(start -0.8636 -0.4064)
			(end -1.1938 -0.4064)
			(stroke
				(width 0.1)
				(type default)
			)
			(layer "B.Fab")
		)
		(fp_line
			(start -0.8636 -0.4572)
			(end -0.8636 -0.4064)
			(stroke
				(width 0.1)
				(type default)
			)
			(layer "B.Fab")
		)
		(fp_line
			(start -1.1938 0.4064)
			(end -0.8636 0.4064)
			(stroke
				(width 0.1)
				(type default)
			)
			(layer "B.Fab")
		)
		(fp_line
			(start -1.1938 -0.4064)
			(end -1.1938 0.4064)
			(stroke
				(width 0.1)
				(type default)
			)
			(layer "B.Fab")
		)
		(pad "1" smd rect
			(at 0.7366 0 90)
			(size 0.7112 0.8128)
			(layers "B.Cu" "B.Mask" "B.Paste")
			(net "PVCCFA_EHV_CPU0")
		)
		(pad "2" smd rect
			(at -0.7366 0 90)
			(size 0.7112 0.8128)
			(layers "B.Cu" "B.Mask" "B.Paste")
			(net "GND")
		)
	)
	(footprint ""
		(layer "B.Cu")
		(at 352.430334 -326.867012 -90)
		(property "Reference" "PC326"
			(at 0 0 90)
			(layer "B.SilkS")
			(hide yes)
			(effects
				(font
					(size 1.27 1.27)
				)
				(justify mirror)
			)
		)
		(property "Value" ""
			(at 0 0 90)
			(layer "B.Fab")
			(effects
				(font
					(size 1.27 1.27)
				)
				(justify mirror)
			)
		)
		(duplicate_pad_numbers_are_jumpers no)
		(fp_line
			(start -4.533392 2.249932)
			(end 4.533392 2.249932)
			(stroke
				(width 0.1524)
				(type default)
			)
			(layer "B.SilkS")
		)
		(fp_line
			(start 4.533392 2.249932)
			(end 4.533392 -2.249932)
			(stroke
				(width 0.1524)
				(type default)
			)
			(layer "B.SilkS")
		)
		(fp_line
			(start -4.533392 -2.249932)
			(end -4.533392 2.249932)
			(stroke
				(width 0.1524)
				(type default)
			)
			(layer "B.SilkS")
		)
		(fp_line
			(start 4.533392 -2.249932)
			(end -4.533392 -2.249932)
			(stroke
				(width 0.1524)
				(type default)
			)
			(layer "B.SilkS")
		)
		(fp_rect
			(start 5.39242 2.326132)
			(end 4.533392 -2.326132)
			(stroke
				(width 0)
				(type default)
			)
			(fill yes)
			(layer "B.SilkS")
		)
		(fp_line
			(start -3.750056 2.249932)
			(end 3.750056 2.249932)
			(stroke
				(width 0.1)
				(type default)
			)
			(layer "B.Fab")
		)
		(fp_line
			(start 3.750056 2.249932)
			(end 3.750056 -2.249932)
			(stroke
				(width 0.1)
				(type default)
			)
			(layer "B.Fab")
		)
		(fp_line
			(start -3.750056 -2.249932)
			(end -3.750056 2.249932)
			(stroke
				(width 0.1)
				(type default)
			)
			(layer "B.Fab")
		)
		(fp_line
			(start 3.750056 -2.249932)
			(end -3.750056 -2.249932)
			(stroke
				(width 0.1)
				(type default)
			)
			(layer "B.Fab")
		)
		(fp_text user "-"
			(at -4.702556 1.251204 270)
			(unlocked yes)
			(layer "B.SilkS")
			(effects
				(font
					(size 1.905 1.4224)
					(thickness 0.1524)
				)
				(justify left mirror)
			)
		)
		(fp_text user "+"
			(at 6.322314 0.786384 180)
			(unlocked yes)
			(layer "B.SilkS")
			(effects
				(font
					(size 1.905 1.4224)
					(thickness 0.1524)
				)
				(justify left mirror)
			)
		)
		(fp_text user "+"
			(at 6.322314 0.786384 180)
			(unlocked yes)
			(layer "B.Fab")
			(effects
				(font
					(size 1.905 1.4224)
					(thickness 0.1524)
				)
				(justify left mirror)
			)
		)
		(fp_text user "-"
			(at -4.8514 -0.14605 270)
			(unlocked yes)
			(layer "B.Fab")
			(effects
				(font
					(size 1.905 1.4224)
					(thickness 0.1524)
				)
				(justify left mirror)
			)
		)
		(pad "1" smd rect
			(at 3.199892 0 90)
			(size 2.413 2.8194)
			(layers "B.Cu" "B.Mask" "B.Paste")
			(net "PVCCIN_CPU0")
		)
		(pad "2" smd rect
			(at -3.199892 0 90)
			(size 2.413 2.8194)
			(layers "B.Cu" "B.Mask" "B.Paste")
			(net "GND")
		)
	)
	(footprint ""
		(layer "B.Cu")
		(at 237.40618 -132.422392)
		(property "Reference" "R577"
			(at 0 0 0)
			(layer "B.SilkS")
			(hide yes)
			(effects
				(font
					(size 1.27 1.27)
				)
				(justify mirror)
			)
		)
		(property "Value" ""
			(at 0 0 0)
			(layer "B.Fab")
			(effects
				(font
					(size 1.27 1.27)
				)
				(justify mirror)
			)
		)
		(duplicate_pad_numbers_are_jumpers no)
		(fp_line
			(start -0.7874 -0.4064)
			(end -0.7874 0.4064)
			(stroke
				(width 0.1524)
				(type default)
			)
			(layer "B.SilkS")
		)
		(fp_line
			(start -0.7874 0.4064)
			(end 0.7874 0.4064)
			(stroke
				(width 0.1524)
				(type default)
			)
			(layer "B.SilkS")
		)
		(fp_line
			(start 0.7874 -0.4064)
			(end -0.7874 -0.4064)
			(stroke
				(width 0.1524)
				(type default)
			)
			(layer "B.SilkS")
		)
		(fp_line
			(start 0.7874 0.4064)
			(end 0.7874 -0.4064)
			(stroke
				(width 0.1524)
				(type default)
			)
			(layer "B.SilkS")
		)
		(fp_line
			(start -0.67945 -0.3048)
			(end -0.67945 0.3048)
			(stroke
				(width 0.1)
				(type default)
			)
			(layer "B.Fab")
		)
		(fp_line
			(start -0.67945 0.3048)
			(end -0.120396 0.3048)
			(stroke
				(width 0.1)
				(type default)
			)
			(layer "B.Fab")
		)
		(fp_line
			(start -0.12065 -0.3048)
			(end -0.67945 -0.3048)
			(stroke
				(width 0.1)
				(type default)
			)
			(layer "B.Fab")
		)
		(fp_line
			(start -0.12065 -0.2794)
			(end -0.12065 -0.3048)
			(stroke
				(width 0.1)
				(type default)
			)
			(layer "B.Fab")
		)
		(fp_line
			(start -0.120396 0.2794)
			(end 0.12065 0.2794)
			(stroke
				(width 0.1)
				(type default)
			)
			(layer "B.Fab")
		)
		(fp_line
			(start -0.120396 0.3048)
			(end -0.120396 0.2794)
			(stroke
				(width 0.1)
				(type default)
			)
			(layer "B.Fab")
		)
		(fp_line
			(start 0.12065 -0.305054)
			(end 0.12065 -0.2794)
			(stroke
				(width 0.1)
				(type default)
			)
			(layer "B.Fab")
		)
		(fp_line
			(start 0.12065 -0.2794)
			(end -0.12065 -0.2794)
			(stroke
				(width 0.1)
				(type default)
			)
			(layer "B.Fab")
		)
		(fp_line
			(start 0.12065 0.2794)
			(end 0.12065 0.3048)
			(stroke
				(width 0.1)
				(type default)
			)
			(layer "B.Fab")
		)
		(fp_line
			(start 0.12065 0.3048)
			(end 0.67945 0.3048)
			(stroke
				(width 0.1)
				(type default)
			)
			(layer "B.Fab")
		)
		(fp_line
			(start 0.67945 -0.305054)
			(end 0.12065 -0.305054)
			(stroke
				(width 0.1)
				(type default)
			)
			(layer "B.Fab")
		)
		(fp_line
			(start 0.67945 0.3048)
			(end 0.67945 -0.305054)
			(stroke
				(width 0.1)
				(type default)
			)
			(layer "B.Fab")
		)
		(pad "1" smd circle
			(at 0.40005 0 180)
			(size 0 0)
			(layers "B.Cu" "B.Mask" "B.Paste")
			(net "SMB_HOST_3V3AUX_SCL_R4")
		)
		(pad "2" smd circle
			(at -0.40005 0 180)
			(size 0 0)
			(layers "B.Cu" "B.Mask" "B.Paste")
			(net "SMB_HOST_3V3AUX_SCL_R")
		)
	)
	(footprint ""
		(layer "B.Cu")
		(at 351.841308 -248.498106 -90)
		(property "Reference" "C495"
			(at 0 0 90)
			(layer "B.SilkS")
			(hide yes)
			(effects
				(font
					(size 1.27 1.27)
				)
				(justify mirror)
			)
		)
		(property "Value" ""
			(at 0 0 90)
			(layer "B.Fab")
			(effects
				(font
					(size 1.27 1.27)
				)
				(justify mirror)
			)
		)
		(duplicate_pad_numbers_are_jumpers no)
		(fp_line
			(start -1.524 0.762)
			(end 1.524 0.762)
			(stroke
				(width 0.1524)
				(type default)
			)
			(layer "B.SilkS")
		)
		(fp_line
			(start 1.524 0.762)
			(end 1.524 -0.762)
			(stroke
				(width 0.1524)
				(type default)
			)
			(layer "B.SilkS")
		)
		(fp_line
			(start -1.524 -0.762)
			(end -1.524 0.762)
			(stroke
				(width 0.1524)
				(type default)
			)
			(layer "B.SilkS")
		)
		(fp_line
			(start 1.524 -0.762)
			(end -1.524 -0.762)
			(stroke
				(width 0.1524)
				(type default)
			)
			(layer "B.SilkS")
		)
		(fp_line
			(start -1.1049 0.724916)
			(end -1.1049 -0.724916)
			(stroke
				(width 0.1)
				(type default)
			)
			(layer "B.Fab")
		)
		(fp_line
			(start 1.1049 0.724916)
			(end -1.1049 0.724916)
			(stroke
				(width 0.1)
				(type default)
			)
			(layer "B.Fab")
		)
		(fp_line
			(start -1.1049 -0.724916)
			(end 1.1049 -0.724916)
			(stroke
				(width 0.1)
				(type default)
			)
			(layer "B.Fab")
		)
		(fp_line
			(start 1.1049 -0.724916)
			(end 1.1049 0.724916)
			(stroke
				(width 0.1)
				(type default)
			)
			(layer "B.Fab")
		)
		(pad "1" smd rect
			(at 0.889 0 270)
			(size 1.016 1.27)
			(layers "B.Cu" "B.Mask" "B.Paste")
			(net "PVCCD_HV_CPU0")
		)
		(pad "2" smd rect
			(at -0.889 0 270)
			(size 1.016 1.27)
			(layers "B.Cu" "B.Mask" "B.Paste")
			(net "GND")
		)
	)
	(footprint ""
		(layer "B.Cu")
		(at 378.80036 -341.218012 -90)
		(property "Reference" "PC263_P0_5"
			(at 0 0 90)
			(layer "B.SilkS")
			(hide yes)
			(effects
				(font
					(size 1.27 1.27)
				)
				(justify mirror)
			)
		)
		(property "Value" ""
			(at 0 0 90)
			(layer "B.Fab")
			(effects
				(font
					(size 1.27 1.27)
				)
				(justify mirror)
			)
		)
		(duplicate_pad_numbers_are_jumpers no)
		(fp_line
			(start -1.524 0.762)
			(end 1.524 0.762)
			(stroke
				(width 0.1524)
				(type default)
			)
			(layer "B.SilkS")
		)
		(fp_line
			(start 1.524 0.762)
			(end 1.524 -0.762)
			(stroke
				(width 0.1524)
				(type default)
			)
			(layer "B.SilkS")
		)
		(fp_line
			(start -1.524 -0.762)
			(end -1.524 0.762)
			(stroke
				(width 0.1524)
				(type default)
			)
			(layer "B.SilkS")
		)
		(fp_line
			(start 1.524 -0.762)
			(end -1.524 -0.762)
			(stroke
				(width 0.1524)
				(type default)
			)
			(layer "B.SilkS")
		)
		(fp_line
			(start -1.1049 0.724916)
			(end -1.1049 -0.724916)
			(stroke
				(width 0.1)
				(type default)
			)
			(layer "B.Fab")
		)
		(fp_line
			(start 1.1049 0.724916)
			(end -1.1049 0.724916)
			(stroke
				(width 0.1)
				(type default)
			)
			(layer "B.Fab")
		)
		(fp_line
			(start -1.1049 -0.724916)
			(end 1.1049 -0.724916)
			(stroke
				(width 0.1)
				(type default)
			)
			(layer "B.Fab")
		)
		(fp_line
			(start 1.1049 -0.724916)
			(end 1.1049 0.724916)
			(stroke
				(width 0.1)
				(type default)
			)
			(layer "B.Fab")
		)
		(pad "1" smd rect
			(at 0.889 0 270)
			(size 1.016 1.27)
			(layers "B.Cu" "B.Mask" "B.Paste")
			(net "SW_P12V_PVCCIN_CPU0_FLT")
		)
		(pad "2" smd rect
			(at -0.889 0 270)
			(size 1.016 1.27)
			(layers "B.Cu" "B.Mask" "B.Paste")
			(net "GND")
		)
	)
	(footprint ""
		(layer "B.Cu")
		(at 321.747642 -26.71064 -90)
		(property "Reference" "R621"
			(at 0 0 90)
			(layer "B.SilkS")
			(hide yes)
			(effects
				(font
					(size 1.27 1.27)
				)
				(justify mirror)
			)
		)
		(property "Value" ""
			(at 0 0 90)
			(layer "B.Fab")
			(effects
				(font
					(size 1.27 1.27)
				)
				(justify mirror)
			)
		)
		(duplicate_pad_numbers_are_jumpers no)
		(fp_line
			(start -0.7874 0.4064)
			(end 0.7874 0.4064)
			(stroke
				(width 0.1524)
				(type default)
			)
			(layer "B.SilkS")
		)
		(fp_line
			(start 0.7874 0.4064)
			(end 0.7874 -0.4064)
			(stroke
				(width 0.1524)
				(type default)
			)
			(layer "B.SilkS")
		)
		(fp_line
			(start -0.7874 -0.4064)
			(end -0.7874 0.4064)
			(stroke
				(width 0.1524)
				(type default)
			)
			(layer "B.SilkS")
		)
		(fp_line
			(start 0.7874 -0.4064)
			(end -0.7874 -0.4064)
			(stroke
				(width 0.1524)
				(type default)
			)
			(layer "B.SilkS")
		)
		(fp_line
			(start -0.67945 0.3048)
			(end -0.120396 0.3048)
			(stroke
				(width 0.1)
				(type default)
			)
			(layer "B.Fab")
		)
		(fp_line
			(start -0.120396 0.3048)
			(end -0.120396 0.2794)
			(stroke
				(width 0.1)
				(type default)
			)
			(layer "B.Fab")
		)
		(fp_line
			(start 0.12065 0.3048)
			(end 0.67945 0.3048)
			(stroke
				(width 0.1)
				(type default)
			)
			(layer "B.Fab")
		)
		(fp_line
			(start 0.67945 0.3048)
			(end 0.67945 -0.305054)
			(stroke
				(width 0.1)
				(type default)
			)
			(layer "B.Fab")
		)
		(fp_line
			(start -0.120396 0.2794)
			(end 0.12065 0.2794)
			(stroke
				(width 0.1)
				(type default)
			)
			(layer "B.Fab")
		)
		(fp_line
			(start 0.12065 0.2794)
			(end 0.12065 0.3048)
			(stroke
				(width 0.1)
				(type default)
			)
			(layer "B.Fab")
		)
		(fp_line
			(start -0.12065 -0.2794)
			(end -0.12065 -0.3048)
			(stroke
				(width 0.1)
				(type default)
			)
			(layer "B.Fab")
		)
		(fp_line
			(start 0.12065 -0.2794)
			(end -0.12065 -0.2794)
			(stroke
				(width 0.1)
				(type default)
			)
			(layer "B.Fab")
		)
		(fp_line
			(start -0.67945 -0.3048)
			(end -0.67945 0.3048)
			(stroke
				(width 0.1)
				(type default)
			)
			(layer "B.Fab")
		)
		(fp_line
			(start -0.12065 -0.3048)
			(end -0.67945 -0.3048)
			(stroke
				(width 0.1)
				(type default)
			)
			(layer "B.Fab")
		)
		(fp_line
			(start 0.12065 -0.305054)
			(end 0.12065 -0.2794)
			(stroke
				(width 0.1)
				(type default)
			)
			(layer "B.Fab")
		)
		(fp_line
			(start 0.67945 -0.305054)
			(end 0.12065 -0.305054)
			(stroke
				(width 0.1)
				(type default)
			)
			(layer "B.Fab")
		)
		(pad "1" smd circle
			(at 0.40005 0 90)
			(size 0 0)
			(layers "B.Cu" "B.Mask" "B.Paste")
			(net "P3V3_AUX")
		)
		(pad "2" smd circle
			(at -0.40005 0 90)
			(size 0 0)
			(layers "B.Cu" "B.Mask" "B.Paste")
			(net "FM_PCH_SKIP_RTC_CLOCK")
		)
	)
	(footprint ""
		(layer "B.Cu")
		(at 409.197556 -318.755776)
		(property "Reference" "R35"
			(at 0 0 0)
			(layer "B.SilkS")
			(hide yes)
			(effects
				(font
					(size 1.27 1.27)
				)
				(justify mirror)
			)
		)
		(property "Value" ""
			(at 0 0 0)
			(layer "B.Fab")
			(effects
				(font
					(size 1.27 1.27)
				)
				(justify mirror)
			)
		)
		(duplicate_pad_numbers_are_jumpers no)
		(fp_line
			(start -0.7874 -0.4064)
			(end -0.7874 0.4064)
			(stroke
				(width 0.1524)
				(type default)
			)
			(layer "B.SilkS")
		)
		(fp_line
			(start -0.7874 0.4064)
			(end 0.7874 0.4064)
			(stroke
				(width 0.1524)
				(type default)
			)
			(layer "B.SilkS")
		)
		(fp_line
			(start 0.7874 -0.4064)
			(end -0.7874 -0.4064)
			(stroke
				(width 0.1524)
				(type default)
			)
			(layer "B.SilkS")
		)
		(fp_line
			(start 0.7874 0.4064)
			(end 0.7874 -0.4064)
			(stroke
				(width 0.1524)
				(type default)
			)
			(layer "B.SilkS")
		)
		(fp_line
			(start -0.67945 -0.3048)
			(end -0.67945 0.3048)
			(stroke
				(width 0.1)
				(type default)
			)
			(layer "B.Fab")
		)
		(fp_line
			(start -0.67945 0.3048)
			(end -0.120396 0.3048)
			(stroke
				(width 0.1)
				(type default)
			)
			(layer "B.Fab")
		)
		(fp_line
			(start -0.12065 -0.3048)
			(end -0.67945 -0.3048)
			(stroke
				(width 0.1)
				(type default)
			)
			(layer "B.Fab")
		)
		(fp_line
			(start -0.12065 -0.2794)
			(end -0.12065 -0.3048)
			(stroke
				(width 0.1)
				(type default)
			)
			(layer "B.Fab")
		)
		(fp_line
			(start -0.120396 0.2794)
			(end 0.12065 0.2794)
			(stroke
				(width 0.1)
				(type default)
			)
			(layer "B.Fab")
		)
		(fp_line
			(start -0.120396 0.3048)
			(end -0.120396 0.2794)
			(stroke
				(width 0.1)
				(type default)
			)
			(layer "B.Fab")
		)
		(fp_line
			(start 0.12065 -0.305054)
			(end 0.12065 -0.2794)
			(stroke
				(width 0.1)
				(type default)
			)
			(layer "B.Fab")
		)
		(fp_line
			(start 0.12065 -0.2794)
			(end -0.12065 -0.2794)
			(stroke
				(width 0.1)
				(type default)
			)
			(layer "B.Fab")
		)
		(fp_line
			(start 0.12065 0.2794)
			(end 0.12065 0.3048)
			(stroke
				(width 0.1)
				(type default)
			)
			(layer "B.Fab")
		)
		(fp_line
			(start 0.12065 0.3048)
			(end 0.67945 0.3048)
			(stroke
				(width 0.1)
				(type default)
			)
			(layer "B.Fab")
		)
		(fp_line
			(start 0.67945 -0.305054)
			(end 0.12065 -0.305054)
			(stroke
				(width 0.1)
				(type default)
			)
			(layer "B.Fab")
		)
		(fp_line
			(start 0.67945 0.3048)
			(end 0.67945 -0.305054)
			(stroke
				(width 0.1)
				(type default)
			)
			(layer "B.Fab")
		)
		(pad "1" smd circle
			(at 0.40005 0 180)
			(size 0 0)
			(layers "B.Cu" "B.Mask" "B.Paste")
			(net "PD_CHE_CPU0_DIMM2_SAA")
		)
		(pad "2" smd circle
			(at -0.40005 0 180)
			(size 0 0)
			(layers "B.Cu" "B.Mask" "B.Paste")
			(net "GND")
		)
	)
)
